# BASEBOARD_FAB2 (Tioga Pass) — schematic netlist excerpt (pin names and nets, part order shuffled) for the footprints in the layout excerpt that follows; sources: Cadence DE-HDL packaged netlist, KiCad conversion of Wiwynn_Tioga_Pass_MB.brd

C8P16  CAP  47UF 4V 20% X6S  pkg 0805  page 76 : A = PVCCIN_CPU1 ; B = GND
R3P13  RES  100.0 1% CHIP  pkg 0402  page 211 : A = PVCCIO_CPU0 ; B = SVID_DIO0_CPU0_R
R9P21  RES  0.0 5% CHIP  pkg 0402  page 200 : A = A_HSC_TIMER ; B = A_HSC_TIMER_R

(kicad_pcb
	(version 20260206)
	(generator "pcbnew")
	(generator_version "10.0")
	(general
		(thickness 1.6)
		(legacy_teardrops no)
	)
	(paper "A4")
	(title_block
		(title "Wiwynn_Tioga_Pass_MB.brd")
		(comment 1 "Tioga Pass / footprints 3541-3543 of 4770")
	)
	(layers
		(0 "F.Cu" signal "TOP")
		(4 "In1.Cu" signal "L2GND")
		(6 "In2.Cu" signal "L3")
		(8 "In3.Cu" signal "L4GND")
		(10 "In4.Cu" signal "L5")
		(12 "In5.Cu" signal "L6GND")
		(14 "In6.Cu" signal "L7VCC")
		(16 "In7.Cu" signal "L8VCC")
		(18 "In8.Cu" signal "L9GND")
		(20 "In9.Cu" signal "L10")
		(22 "In10.Cu" signal "L11GND")
		(24 "In11.Cu" signal "L12")
		(26 "In12.Cu" signal "L13GND")
		(2 "B.Cu" signal "BOTTOM")
		(9 "F.Adhes" user "F.Adhesive")
		(11 "B.Adhes" user "B.Adhesive")
		(13 "F.Paste" user "Package Geometry/Pastemask Top")
		(15 "B.Paste" user "Package Geometry/Pastemask Bottom")
		(5 "F.SilkS" user "Ref Des/Silkscreen Top")
		(7 "B.SilkS" user "Ref Des/Silkscreen Bottom")
		(1 "F.Mask" user "Board Geometry/Soldermask Top")
		(3 "B.Mask" user "Board Geometry/Soldermask Bottom")
		(17 "Dwgs.User" user "User.Drawings")
		(19 "Cmts.User" user "User.Comments")
		(21 "Eco1.User" user "User.Eco1")
		(23 "Eco2.User" user "User.Eco2")
		(25 "Edge.Cuts" user "Board Geometry/Outline")
		(27 "Margin" user)
		(31 "F.CrtYd" user "Package Geometry/Place Bound Top")
		(29 "B.CrtYd" user "Package Geometry/Place Bound Bottom")
		(35 "F.Fab" user "Ref Des/Assembly Top")
		(33 "B.Fab" user "Ref Des/Assembly Bottom")
	)
	(footprint ""
		(layer "B.Cu")
		(at 340.3092 -87.1982 180)
		(property "Reference" "R3P13"
			(at 0 0 0)
			(layer "B.SilkS")
			(hide yes)
			(effects
				(font
					(size 1.27 1.27)
				)
				(justify mirror)
			)
		)
		(property "Value" ""
			(at 0 0 0)
			(layer "B.Fab")
			(effects
				(font
					(size 1.27 1.27)
				)
				(justify mirror)
			)
		)
		(duplicate_pad_numbers_are_jumpers no)
		(fp_poly
			(pts
				(xy 0.2794 -0.1016) (xy -0.2794 -0.1016) (xy -0.2794 0.9906) (xy 0.2794 0.9906)
			)
			(stroke
				(width 0)
				(type default)
			)
			(fill no)
			(layer "B.CrtYd")
		)
		(fp_line
			(start 0.2794 0.9906)
			(end -0.2794 0.9906)
			(stroke
				(width 0.1)
				(type default)
			)
			(layer "B.Fab")
		)
		(fp_line
			(start 0.2794 -0.1016)
			(end 0.2794 0.9906)
			(stroke
				(width 0.1)
				(type default)
			)
			(layer "B.Fab")
		)
		(fp_line
			(start -0.2794 0.9906)
			(end -0.2794 -0.1016)
			(stroke
				(width 0.1)
				(type default)
			)
			(layer "B.Fab")
		)
		(fp_line
			(start -0.2794 -0.1016)
			(end 0.2794 -0.1016)
			(stroke
				(width 0.1)
				(type default)
			)
			(layer "B.Fab")
		)
		(pad "1" smd rect
			(at 0 0)
			(size 0.508 0.508)
			(layers "B.Cu" "B.Mask" "B.Paste")
			(net "PVCCIO_CPU0")
		)
		(pad "2" smd rect
			(at 0 0.889)
			(size 0.508 0.508)
			(layers "B.Cu" "B.Mask" "B.Paste")
			(net "SVID_DIO0_CPU0_R")
		)
		(zone
			(layer "B.Cu")
			(hatch none 0.5)
			(connect_pads
				(clearance 0)
			)
			(min_thickness 0.25)
			(keepout
				(tracks not_allowed)
				(vias allowed)
				(pads allowed)
				(copperpour not_allowed)
				(footprints allowed)
			)
			(placement
				(enabled no)
				(sheetname "")
			)
			(fill
				(thermal_gap 0.5)
				(thermal_bridge_width 0.5)
				(island_removal_mode 0)
			)
			(polygon
				(pts
					(xy 340.0552 -87.8332) (xy 340.5632 -87.8332) (xy 340.5632 -87.4522) (xy 340.0552 -87.4522)
				)
			)
		)
		(zone
			(layer "B.Cu")
			(hatch none 0.5)
			(connect_pads
				(clearance 0)
			)
			(min_thickness 0.25)
			(keepout
				(tracks allowed)
				(vias not_allowed)
				(pads allowed)
				(copperpour not_allowed)
				(footprints allowed)
			)
			(placement
				(enabled no)
				(sheetname "")
			)
			(fill
				(thermal_gap 0.5)
				(thermal_bridge_width 0.5)
				(island_removal_mode 0)
			)
			(polygon
				(pts
					(xy 340.0552 -87.4522) (xy 340.5632 -87.4522) (xy 340.5632 -87.8332) (xy 340.0552 -87.8332)
				)
			)
		)
	)
	(footprint ""
		(layer "B.Cu")
		(at 23.876 -77.089 180)
		(property "Reference" "R9P21"
			(at 0 0 0)
			(layer "B.SilkS")
			(hide yes)
			(effects
				(font
					(size 1.27 1.27)
				)
				(justify mirror)
			)
		)
		(property "Value" ""
			(at 0 0 0)
			(layer "B.Fab")
			(effects
				(font
					(size 1.27 1.27)
				)
				(justify mirror)
			)
		)
		(duplicate_pad_numbers_are_jumpers no)
		(fp_poly
			(pts
				(xy 0.2794 -0.1016) (xy -0.2794 -0.1016) (xy -0.2794 0.9906) (xy 0.2794 0.9906)
			)
			(stroke
				(width 0)
				(type default)
			)
			(fill no)
			(layer "B.CrtYd")
		)
		(fp_line
			(start 0.2794 0.9906)
			(end -0.2794 0.9906)
			(stroke
				(width 0.1)
				(type default)
			)
			(layer "B.Fab")
		)
		(fp_line
			(start 0.2794 -0.1016)
			(end 0.2794 0.9906)
			(stroke
				(width 0.1)
				(type default)
			)
			(layer "B.Fab")
		)
		(fp_line
			(start -0.2794 0.9906)
			(end -0.2794 -0.1016)
			(stroke
				(width 0.1)
				(type default)
			)
			(layer "B.Fab")
		)
		(fp_line
			(start -0.2794 -0.1016)
			(end 0.2794 -0.1016)
			(stroke
				(width 0.1)
				(type default)
			)
			(layer "B.Fab")
		)
		(pad "1" smd rect
			(at 0 0)
			(size 0.508 0.508)
			(layers "B.Cu" "B.Mask" "B.Paste")
			(net "A_HSC_TIMER")
		)
		(pad "2" smd rect
			(at 0 0.889)
			(size 0.508 0.508)
			(layers "B.Cu" "B.Mask" "B.Paste")
			(net "A_HSC_TIMER_R")
		)
		(zone
			(layer "B.Cu")
			(hatch none 0.5)
			(connect_pads
				(clearance 0)
			)
			(min_thickness 0.25)
			(keepout
				(tracks not_allowed)
				(vias allowed)
				(pads allowed)
				(copperpour not_allowed)
				(footprints allowed)
			)
			(placement
				(enabled no)
				(sheetname "")
			)
			(fill
				(thermal_gap 0.5)
				(thermal_bridge_width 0.5)
				(island_removal_mode 0)
			)
			(polygon
				(pts
					(xy 23.622 -77.724) (xy 24.13 -77.724) (xy 24.13 -77.343) (xy 23.622 -77.343)
				)
			)
		)
		(zone
			(layer "B.Cu")
			(hatch none 0.5)
			(connect_pads
				(clearance 0)
			)
			(min_thickness 0.25)
			(keepout
				(tracks allowed)
				(vias not_allowed)
				(pads allowed)
				(copperpour not_allowed)
				(footprints allowed)
			)
			(placement
				(enabled no)
				(sheetname "")
			)
			(fill
				(thermal_gap 0.5)
				(thermal_bridge_width 0.5)
				(island_removal_mode 0)
			)
			(polygon
				(pts
					(xy 23.622 -77.343) (xy 24.13 -77.343) (xy 24.13 -77.724) (xy 23.622 -77.724)
				)
			)
		)
	)
	(footprint ""
		(layer "B.Cu")
		(at 102.692454 -77.82814)
		(property "Reference" "C8P16"
			(at 0 0 0)
			(layer "B.SilkS")
			(hide yes)
			(effects
				(font
					(size 1.27 1.27)
				)
				(justify mirror)
			)
		)
		(property "Value" ""
			(at 0 0 0)
			(layer "B.Fab")
			(effects
				(font
					(size 1.27 1.27)
				)
				(justify mirror)
			)
		)
		(duplicate_pad_numbers_are_jumpers no)
		(fp_poly
			(pts
				(xy 0.7239 -0.2159) (xy -0.7239 -0.2159) (xy -0.7239 1.9939) (xy 0.7239 1.9939)
			)
			(stroke
				(width 0)
				(type default)
			)
			(fill no)
			(layer "B.CrtYd")
		)
		(fp_line
			(start -0.7239 -0.2159)
			(end 0.7239 -0.2159)
			(stroke
				(width 0.1)
				(type default)
			)
			(layer "B.Fab")
		)
		(fp_line
			(start -0.7239 1.9939)
			(end -0.7239 -0.2159)
			(stroke
				(width 0.1)
				(type default)
			)
			(layer "B.Fab")
		)
		(fp_line
			(start 0.7239 -0.2159)
			(end 0.7239 1.9939)
			(stroke
				(width 0.1)
				(type default)
			)
			(layer "B.Fab")
		)
		(fp_line
			(start 0.7239 1.9939)
			(end -0.7239 1.9939)
			(stroke
				(width 0.1)
				(type default)
			)
			(layer "B.Fab")
		)
		(pad "1" smd rect
			(at 0 0 180)
			(size 1.27 1.016)
			(layers "B.Cu" "B.Mask" "B.Paste")
			(net "PVCCIN_CPU1")
		)
		(pad "2" smd rect
			(at 0 1.778 180)
			(size 1.27 1.016)
			(layers "B.Cu" "B.Mask" "B.Paste")
			(net "GND")
		)
		(zone
			(layer "B.Cu")
			(hatch none 0.5)
			(connect_pads
				(clearance 0)
			)
			(min_thickness 0.25)
			(keepout
				(tracks not_allowed)
				(vias allowed)
				(pads allowed)
				(copperpour not_allowed)
				(footprints allowed)
			)
			(placement
				(enabled no)
				(sheetname "")
			)
			(fill
				(thermal_gap 0.5)
				(thermal_bridge_width 0.5)
				(island_removal_mode 0)
			)
			(polygon
				(pts
					(xy 103.327454 -77.32014) (xy 102.057454 -77.32014) (xy 102.057454 -76.55814) (xy 103.327454 -76.55814)
				)
			)
		)
	)
)
